# T6G (Grand Teton) — schematic netlist excerpt (pin names and nets, part order shuffled) for the footprints in the layout excerpt that follows; sources: Cadence DE-HDL packaged netlist, KiCad conversion of 04192023_DAF0TMB3IC0_F0TG_MB_C_brd_V02_OCP.brd

R30  Q_RES  0 5% CHIP  pkg 0402LF  page 28 : A = SMB_CPU0_3_R_SDA ; B = SMB_CPU0_3_SDA

DB5  TDR_3P  EMPTY  pkg TH2  page 260
  GND  = T1_GND
  IO1  = TDR_SE_45_OHM_IN4
  IO2  = TDR_SE_45_OHM_IN4

(kicad_pcb
	(version 20260206)
	(generator "pcbnew")
	(generator_version "10.0")
	(general
		(thickness 1.6)
		(legacy_teardrops no)
	)
	(paper "A4")
	(title_block
		(title "04192023_DAF0TMB3IC0_F0TG_MB_C_brd_V02_OCP.brd")
		(comment 1 "Grand Teton / footprints 8268-8269 of 8354")
	)
	(layers
		(0 "F.Cu" signal "TOP")
		(4 "In1.Cu" signal "GND")
		(6 "In2.Cu" signal "IN1")
		(8 "In3.Cu" signal "GND1")
		(10 "In4.Cu" signal "IN2")
		(12 "In5.Cu" signal "GND2")
		(14 "In6.Cu" signal "IN3")
		(16 "In7.Cu" signal "GND3")
		(18 "In8.Cu" signal "VCC")
		(20 "In9.Cu" signal "VCC1")
		(22 "In10.Cu" signal "GND4")
		(24 "In11.Cu" signal "IN4")
		(26 "In12.Cu" signal "GND5")
		(28 "In13.Cu" signal "IN5")
		(30 "In14.Cu" signal "GND6")
		(32 "In15.Cu" signal "IN6")
		(34 "In16.Cu" signal "GND7")
		(2 "B.Cu" signal "BOTTOM")
		(9 "F.Adhes" user "F.Adhesive")
		(11 "B.Adhes" user "B.Adhesive")
		(13 "F.Paste" user "Package Geometry/Pastemask Top")
		(15 "B.Paste" user "Package Geometry/Pastemask Bottom")
		(5 "F.SilkS" user "Ref Des/Silkscreen Top")
		(7 "B.SilkS" user "Ref Des/Silkscreen Bottom")
		(1 "F.Mask" user "Board Geometry/Soldermask Top")
		(3 "B.Mask" user "Board Geometry/Soldermask Bottom")
		(17 "Dwgs.User" user "User.Drawings")
		(19 "Cmts.User" user "User.Comments")
		(21 "Eco1.User" user "User.Eco1")
		(23 "Eco2.User" user "User.Eco2")
		(25 "Edge.Cuts" user "Board Geometry/Outline")
		(27 "Margin" user)
		(31 "F.CrtYd" user "Package Geometry/Place Bound Top")
		(29 "B.CrtYd" user "Package Geometry/Place Bound Bottom")
		(35 "F.Fab" user "Ref Des/Assembly Top")
		(33 "B.Fab" user "Ref Des/Assembly Bottom")
	)
	(footprint ""
		(layer "B.Cu")
		(at 388.537958 -203.577952 180)
		(property "Reference" "R30"
			(at 0 0 0)
			(layer "B.SilkS")
			(hide yes)
			(effects
				(font
					(size 1.27 1.27)
				)
				(justify mirror)
			)
		)
		(property "Value" ""
			(at 0 0 0)
			(layer "B.Fab")
			(effects
				(font
					(size 1.27 1.27)
				)
				(justify mirror)
			)
		)
		(duplicate_pad_numbers_are_jumpers no)
		(fp_line
			(start 0.7874 0.4064)
			(end 0.7874 -0.4064)
			(stroke
				(width 0.1524)
				(type default)
			)
			(layer "B.SilkS")
		)
		(fp_line
			(start 0.7874 -0.4064)
			(end -0.7874 -0.4064)
			(stroke
				(width 0.1524)
				(type default)
			)
			(layer "B.SilkS")
		)
		(fp_line
			(start -0.7874 0.4064)
			(end 0.7874 0.4064)
			(stroke
				(width 0.1524)
				(type default)
			)
			(layer "B.SilkS")
		)
		(fp_line
			(start -0.7874 -0.4064)
			(end -0.7874 0.4064)
			(stroke
				(width 0.1524)
				(type default)
			)
			(layer "B.SilkS")
		)
		(fp_line
			(start 0.67945 0.3048)
			(end 0.67945 -0.305054)
			(stroke
				(width 0.1)
				(type default)
			)
			(layer "B.Fab")
		)
		(fp_line
			(start 0.67945 -0.305054)
			(end 0.12065 -0.305054)
			(stroke
				(width 0.1)
				(type default)
			)
			(layer "B.Fab")
		)
		(fp_line
			(start 0.12065 0.3048)
			(end 0.67945 0.3048)
			(stroke
				(width 0.1)
				(type default)
			)
			(layer "B.Fab")
		)
		(fp_line
			(start 0.12065 0.2794)
			(end 0.12065 0.3048)
			(stroke
				(width 0.1)
				(type default)
			)
			(layer "B.Fab")
		)
		(fp_line
			(start 0.12065 -0.2794)
			(end -0.12065 -0.2794)
			(stroke
				(width 0.1)
				(type default)
			)
			(layer "B.Fab")
		)
		(fp_line
			(start 0.12065 -0.305054)
			(end 0.12065 -0.2794)
			(stroke
				(width 0.1)
				(type default)
			)
			(layer "B.Fab")
		)
		(fp_line
			(start -0.120396 0.3048)
			(end -0.120396 0.2794)
			(stroke
				(width 0.1)
				(type default)
			)
			(layer "B.Fab")
		)
		(fp_line
			(start -0.120396 0.2794)
			(end 0.12065 0.2794)
			(stroke
				(width 0.1)
				(type default)
			)
			(layer "B.Fab")
		)
		(fp_line
			(start -0.12065 -0.2794)
			(end -0.12065 -0.3048)
			(stroke
				(width 0.1)
				(type default)
			)
			(layer "B.Fab")
		)
		(fp_line
			(start -0.12065 -0.3048)
			(end -0.67945 -0.3048)
			(stroke
				(width 0.1)
				(type default)
			)
			(layer "B.Fab")
		)
		(fp_line
			(start -0.67945 0.3048)
			(end -0.120396 0.3048)
			(stroke
				(width 0.1)
				(type default)
			)
			(layer "B.Fab")
		)
		(fp_line
			(start -0.67945 -0.3048)
			(end -0.67945 0.3048)
			(stroke
				(width 0.1)
				(type default)
			)
			(layer "B.Fab")
		)
		(pad "1" smd circle
			(at 0.40005 0)
			(size 0 0)
			(layers "B.Cu" "B.Mask" "B.Paste")
			(net "SMB_CPU0_3_R_SDA")
		)
		(pad "2" smd circle
			(at -0.40005 0)
			(size 0 0)
			(layers "B.Cu" "B.Mask" "B.Paste")
			(net "SMB_CPU0_3_SDA")
		)
	)
	(footprint ""
		(layer "B.Cu")
		(at 474.16466 -117.700806)
		(property "Reference" "DB5"
			(at 2.584704 -5.768848 270)
			(unlocked yes)
			(layer "B.SilkS")
			(effects
				(font
					(size 0.7874 0.5842)
					(thickness 0.1524)
				)
				(justify left mirror)
			)
		)
		(property "Value" ""
			(at 0 0 0)
			(layer "B.Fab")
			(effects
				(font
					(size 1.27 1.27)
				)
				(justify mirror)
			)
		)
		(duplicate_pad_numbers_are_jumpers no)
		(fp_line
			(start -3.330702 -4.771136)
			(end 0 4.011168)
			(stroke
				(width 0.1524)
				(type default)
			)
			(layer "B.SilkS")
		)
		(fp_line
			(start 0 4.011168)
			(end 2.826766 -3.442462)
			(stroke
				(width 0.1524)
				(type default)
			)
			(layer "B.SilkS")
		)
		(fp_line
			(start 3.18389 -4.383786)
			(end 3.330702 -4.771136)
			(stroke
				(width 0.1524)
				(type default)
			)
			(layer "B.SilkS")
		)
		(fp_line
			(start 3.330702 -4.771136)
			(end -3.330702 -4.771136)
			(stroke
				(width 0.1524)
				(type default)
			)
			(layer "B.SilkS")
		)
		(fp_line
			(start -3.330702 -4.771136)
			(end 0 4.011168)
			(stroke
				(width 0.1)
				(type default)
			)
			(layer "B.Fab")
		)
		(fp_line
			(start 0 4.011168)
			(end 3.330702 -4.771136)
			(stroke
				(width 0.1)
				(type default)
			)
			(layer "B.Fab")
		)
		(fp_line
			(start 3.330702 -4.771136)
			(end -3.330702 -4.771136)
			(stroke
				(width 0.1)
				(type default)
			)
			(layer "B.Fab")
		)
		(pad "1" thru_hole circle
			(at 0 0 180)
			(size 2.159 2.159)
			(drill 1.7018)
			(layers "*.Cu" "*.Mask")
			(remove_unused_layers no)
			(net "T1_GND")
			(clearance 0.0254)
			(thermal_gap 0.0254)
		)
		(pad "2" thru_hole circle
			(at 1.27 -3.348736 180)
			(size 2.159 2.159)
			(drill 1.7018)
			(layers "*.Cu" "*.Mask")
			(remove_unused_layers no)
			(net "TDR_SE_45_OHM_IN4")
			(clearance 0.0254)
			(thermal_gap 0.0254)
		)
		(pad "3" thru_hole circle
			(at -1.27 -3.348736 180)
			(size 2.159 2.159)
			(drill 1.7018)
			(layers "*.Cu" "*.Mask")
			(remove_unused_layers no)
			(net "TDR_SE_45_OHM_IN4")
			(clearance 0.0254)
			(thermal_gap 0.0254)
		)
	)
)
